# S9S_MB_2U (Grand Teton) — schematic netlist excerpt (pin names and nets, part order shuffled) for the footprints in the layout excerpt that follows; sources: Cadence DE-HDL packaged netlist, KiCad conversion of 03242023_DA0F0TMBIJ0_F0T_Motherboard_J_brd_V01_OCP.brd

R3305  Q_RES  0 5% CHIP  pkg 0402LF  page 165 : A = OCP_SFF_RBT_ARB_IN_MUX1 ; B = OCP_SFF_RBT_ARB_IN_MUX1_R
PC586  Q_CAPP  560UF 2.5V 20% OSCON  pkg THLF  page 285 : A = PVCCIN_CPU1 ; B = GND
R1822  Q_RES  10K 1% CHIP  pkg 0402LF  page 231 : A = P3V3_AUX ; B = RST_SMB_SWITCH_N

(kicad_pcb
	(version 20260206)
	(generator "pcbnew")
	(generator_version "10.0")
	(general
		(thickness 1.6)
		(legacy_teardrops no)
	)
	(paper "A4")
	(title_block
		(title "03242023_DA0F0TMBIJ0_F0T_Motherboard_J_brd_V01_OCP.brd")
		(comment 1 "Grand Teton / footprints 4041-4043 of 6105")
	)
	(layers
		(0 "F.Cu" signal "TOP")
		(4 "In1.Cu" signal "GND")
		(6 "In2.Cu" signal "IN1")
		(8 "In3.Cu" signal "GND1")
		(10 "In4.Cu" signal "IN2")
		(12 "In5.Cu" signal "GND2")
		(14 "In6.Cu" signal "IN3")
		(16 "In7.Cu" signal "GND3")
		(18 "In8.Cu" signal "VCC")
		(20 "In9.Cu" signal "VCC1")
		(22 "In10.Cu" signal "GND4")
		(24 "In11.Cu" signal "IN4")
		(26 "In12.Cu" signal "GND5")
		(28 "In13.Cu" signal "IN5")
		(30 "In14.Cu" signal "GND6")
		(32 "In15.Cu" signal "IN6")
		(34 "In16.Cu" signal "GND7")
		(2 "B.Cu" signal "BOTTOM")
		(9 "F.Adhes" user "F.Adhesive")
		(11 "B.Adhes" user "B.Adhesive")
		(13 "F.Paste" user "Package Geometry/Pastemask Top")
		(15 "B.Paste" user "Package Geometry/Pastemask Bottom")
		(5 "F.SilkS" user "Ref Des/Silkscreen Top")
		(7 "B.SilkS" user "Ref Des/Silkscreen Bottom")
		(1 "F.Mask" user "Board Geometry/Soldermask Top")
		(3 "B.Mask" user "Board Geometry/Soldermask Bottom")
		(17 "Dwgs.User" user "User.Drawings")
		(19 "Cmts.User" user "User.Comments")
		(21 "Eco1.User" user "User.Eco1")
		(23 "Eco2.User" user "User.Eco2")
		(25 "Edge.Cuts" user "Board Geometry/Outline")
		(27 "Margin" user)
		(31 "F.CrtYd" user "Package Geometry/Place Bound Top")
		(29 "B.CrtYd" user "Package Geometry/Place Bound Bottom")
		(35 "F.Fab" user "Ref Des/Assembly Top")
		(33 "B.Fab" user "Ref Des/Assembly Bottom")
	)
	(footprint ""
		(layer "F.Cu")
		(at 150.83028 -31.829756 180)
		(property "Reference" "R3305"
			(at 0 0 180)
			(layer "F.SilkS")
			(hide yes)
			(effects
				(font
					(size 1.27 1.27)
				)
			)
		)
		(property "Value" ""
			(at 0 0 180)
			(layer "F.Fab")
			(effects
				(font
					(size 1.27 1.27)
				)
			)
		)
		(duplicate_pad_numbers_are_jumpers no)
		(fp_line
			(start 0.7874 0.4064)
			(end -0.7874 0.4064)
			(stroke
				(width 0.1524)
				(type default)
			)
			(layer "F.SilkS")
		)
		(fp_line
			(start 0.7874 -0.4064)
			(end 0.7874 0.4064)
			(stroke
				(width 0.1524)
				(type default)
			)
			(layer "F.SilkS")
		)
		(fp_line
			(start -0.7874 0.4064)
			(end -0.7874 -0.4064)
			(stroke
				(width 0.1524)
				(type default)
			)
			(layer "F.SilkS")
		)
		(fp_line
			(start -0.7874 -0.4064)
			(end 0.7874 -0.4064)
			(stroke
				(width 0.1524)
				(type default)
			)
			(layer "F.SilkS")
		)
		(fp_line
			(start 0.67945 0.3048)
			(end 0.120396 0.3048)
			(stroke
				(width 0.1)
				(type default)
			)
			(layer "F.Fab")
		)
		(fp_line
			(start 0.67945 -0.3048)
			(end 0.67945 0.3048)
			(stroke
				(width 0.1)
				(type default)
			)
			(layer "F.Fab")
		)
		(fp_line
			(start 0.12065 -0.2794)
			(end 0.12065 -0.3048)
			(stroke
				(width 0.1)
				(type default)
			)
			(layer "F.Fab")
		)
		(fp_line
			(start 0.12065 -0.3048)
			(end 0.67945 -0.3048)
			(stroke
				(width 0.1)
				(type default)
			)
			(layer "F.Fab")
		)
		(fp_line
			(start 0.120396 0.3048)
			(end 0.120396 0.2794)
			(stroke
				(width 0.1)
				(type default)
			)
			(layer "F.Fab")
		)
		(fp_line
			(start 0.120396 0.2794)
			(end -0.12065 0.2794)
			(stroke
				(width 0.1)
				(type default)
			)
			(layer "F.Fab")
		)
		(fp_line
			(start -0.12065 0.3048)
			(end -0.67945 0.3048)
			(stroke
				(width 0.1)
				(type default)
			)
			(layer "F.Fab")
		)
		(fp_line
			(start -0.12065 0.2794)
			(end -0.12065 0.3048)
			(stroke
				(width 0.1)
				(type default)
			)
			(layer "F.Fab")
		)
		(fp_line
			(start -0.12065 -0.2794)
			(end 0.12065 -0.2794)
			(stroke
				(width 0.1)
				(type default)
			)
			(layer "F.Fab")
		)
		(fp_line
			(start -0.12065 -0.305054)
			(end -0.12065 -0.2794)
			(stroke
				(width 0.1)
				(type default)
			)
			(layer "F.Fab")
		)
		(fp_line
			(start -0.67945 0.3048)
			(end -0.67945 -0.305054)
			(stroke
				(width 0.1)
				(type default)
			)
			(layer "F.Fab")
		)
		(fp_line
			(start -0.67945 -0.305054)
			(end -0.12065 -0.305054)
			(stroke
				(width 0.1)
				(type default)
			)
			(layer "F.Fab")
		)
		(pad "1" smd circle
			(at -0.40005 0 180)
			(size 0 0)
			(layers "F.Cu" "F.Mask" "F.Paste")
			(net "OCP_SFF_RBT_ARB_IN_MUX1")
		)
		(pad "2" smd circle
			(at 0.40005 0 180)
			(size 0 0)
			(layers "F.Cu" "F.Mask" "F.Paste")
			(net "OCP_SFF_RBT_ARB_IN_MUX1_R")
		)
	)
	(footprint ""
		(layer "F.Cu")
		(at 110.901226 -315.66739 90)
		(property "Reference" "PC586"
			(at 0 0 90)
			(layer "F.SilkS")
			(hide yes)
			(effects
				(font
					(size 1.27 1.27)
				)
			)
		)
		(property "Value" ""
			(at 0 0 90)
			(layer "F.Fab")
			(effects
				(font
					(size 1.27 1.27)
				)
			)
		)
		(duplicate_pad_numbers_are_jumpers no)
		(fp_line
			(start 2.750058 0.999998)
			(end -2.750058 0.999998)
			(stroke
				(width 0.1524)
				(type default)
			)
			(layer "F.SilkS")
		)
		(fp_circle
			(center 0 0.999998)
			(end 0 3.750056)
			(stroke
				(width 0.1524)
				(type default)
			)
			(fill no)
			(layer "F.SilkS")
		)
		(fp_poly
			(pts
				(arc
					(start 2.750058 0.999998)
					(mid 0 3.750056)
					(end -2.750058 0.999998)
				)
			)
			(stroke
				(width 0)
				(type default)
			)
			(fill yes)
			(layer "F.SilkS")
		)
		(fp_circle
			(center 0 0.999998)
			(end 0 3.750056)
			(stroke
				(width 0.1)
				(type default)
			)
			(fill no)
			(layer "F.Fab")
		)
		(pad "1" thru_hole rect
			(at 0 0 90)
			(size 1.5748 1.5748)
			(drill 1.0668)
			(layers "*.Cu" "*.Mask")
			(remove_unused_layers no)
			(net "PVCCIN_CPU1")
			(clearance 0)
			(padstack
				(mode front_inner_back)
				(layer "Inner"
					(shape circle)
					(size 1.5748 1.5748)
					(clearance 0)
				)
				(layer "B.Cu"
					(shape rect)
					(size 1.5748 1.5748)
					(clearance 0)
				)
			)
		)
		(pad "2" thru_hole circle
			(at 0 1.999996 90)
			(size 1.5748 1.5748)
			(drill 1.0668)
			(layers "*.Cu" "*.Mask")
			(remove_unused_layers no)
			(net "GND")
			(clearance 0)
		)
	)
	(footprint ""
		(layer "F.Cu")
		(at 111.332772 -137.854182)
		(property "Reference" "R1822"
			(at 0 0 0)
			(layer "F.SilkS")
			(hide yes)
			(effects
				(font
					(size 1.27 1.27)
				)
			)
		)
		(property "Value" ""
			(at 0 0 0)
			(layer "F.Fab")
			(effects
				(font
					(size 1.27 1.27)
				)
			)
		)
		(duplicate_pad_numbers_are_jumpers no)
		(fp_line
			(start -0.7874 -0.4064)
			(end 0.7874 -0.4064)
			(stroke
				(width 0.1524)
				(type default)
			)
			(layer "F.SilkS")
		)
		(fp_line
			(start -0.7874 0.4064)
			(end -0.7874 -0.4064)
			(stroke
				(width 0.1524)
				(type default)
			)
			(layer "F.SilkS")
		)
		(fp_line
			(start 0.7874 -0.4064)
			(end 0.7874 0.4064)
			(stroke
				(width 0.1524)
				(type default)
			)
			(layer "F.SilkS")
		)
		(fp_line
			(start 0.7874 0.4064)
			(end -0.7874 0.4064)
			(stroke
				(width 0.1524)
				(type default)
			)
			(layer "F.SilkS")
		)
		(fp_line
			(start -0.67945 -0.305054)
			(end -0.12065 -0.305054)
			(stroke
				(width 0.1)
				(type default)
			)
			(layer "F.Fab")
		)
		(fp_line
			(start -0.67945 0.3048)
			(end -0.67945 -0.305054)
			(stroke
				(width 0.1)
				(type default)
			)
			(layer "F.Fab")
		)
		(fp_line
			(start -0.12065 -0.305054)
			(end -0.12065 -0.2794)
			(stroke
				(width 0.1)
				(type default)
			)
			(layer "F.Fab")
		)
		(fp_line
			(start -0.12065 -0.2794)
			(end 0.12065 -0.2794)
			(stroke
				(width 0.1)
				(type default)
			)
			(layer "F.Fab")
		)
		(fp_line
			(start -0.12065 0.2794)
			(end -0.12065 0.3048)
			(stroke
				(width 0.1)
				(type default)
			)
			(layer "F.Fab")
		)
		(fp_line
			(start -0.12065 0.3048)
			(end -0.67945 0.3048)
			(stroke
				(width 0.1)
				(type default)
			)
			(layer "F.Fab")
		)
		(fp_line
			(start 0.120396 0.2794)
			(end -0.12065 0.2794)
			(stroke
				(width 0.1)
				(type default)
			)
			(layer "F.Fab")
		)
		(fp_line
			(start 0.120396 0.3048)
			(end 0.120396 0.2794)
			(stroke
				(width 0.1)
				(type default)
			)
			(layer "F.Fab")
		)
		(fp_line
			(start 0.12065 -0.3048)
			(end 0.67945 -0.3048)
			(stroke
				(width 0.1)
				(type default)
			)
			(layer "F.Fab")
		)
		(fp_line
			(start 0.12065 -0.2794)
			(end 0.12065 -0.3048)
			(stroke
				(width 0.1)
				(type default)
			)
			(layer "F.Fab")
		)
		(fp_line
			(start 0.67945 -0.3048)
			(end 0.67945 0.3048)
			(stroke
				(width 0.1)
				(type default)
			)
			(layer "F.Fab")
		)
		(fp_line
			(start 0.67945 0.3048)
			(end 0.120396 0.3048)
			(stroke
				(width 0.1)
				(type default)
			)
			(layer "F.Fab")
		)
		(pad "1" smd circle
			(at -0.40005 0)
			(size 0 0)
			(layers "F.Cu" "F.Mask" "F.Paste")
			(net "P3V3_AUX")
		)
		(pad "2" smd circle
			(at 0.40005 0)
			(size 0 0)
			(layers "F.Cu" "F.Mask" "F.Paste")
			(net "RST_SMB_SWITCH_N")
		)
	)
)
